(kicad_pcb
	(version 20260206)
	(generator "pcbnew")
	(generator_version "10.0")
	(general
		(thickness 1.6)
		(legacy_teardrops no)
	)
	(paper "A4")
	(title_block
		(title "Wiwynn_Tioga_Pass_MB.brd")
		(comment 1 "Tioga Pass / footprints 875-882 of 4770")
	)
	(layers
		(0 "F.Cu" signal "TOP")
		(4 "In1.Cu" signal "L2GND")
		(6 "In2.Cu" signal "L3")
		(8 "In3.Cu" signal "L4GND")
		(10 "In4.Cu" signal "L5")
		(12 "In5.Cu" signal "L6GND")
		(14 "In6.Cu" signal "L7VCC")
		(16 "In7.Cu" signal "L8VCC")
		(18 "In8.Cu" signal "L9GND")
		(20 "In9.Cu" signal "L10")
		(22 "In10.Cu" signal "L11GND")
		(24 "In11.Cu" signal "L12")
		(26 "In12.Cu" signal "L13GND")
		(2 "B.Cu" signal "BOTTOM")
		(9 "F.Adhes" user "F.Adhesive")
		(11 "B.Adhes" user "B.Adhesive")
		(13 "F.Paste" user "Package Geometry/Pastemask Top")
		(15 "B.Paste" user "Package Geometry/Pastemask Bottom")
		(5 "F.SilkS" user "Ref Des/Silkscreen Top")
		(7 "B.SilkS" user "Ref Des/Silkscreen Bottom")
		(1 "F.Mask" user "Board Geometry/Soldermask Top")
		(3 "B.Mask" user "Board Geometry/Soldermask Bottom")
		(17 "Dwgs.User" user "User.Drawings")
		(19 "Cmts.User" user "User.Comments")
		(21 "Eco1.User" user "User.Eco1")
		(23 "Eco2.User" user "User.Eco2")
		(25 "Edge.Cuts" user "Board Geometry/Outline")
		(27 "Margin" user)
		(31 "F.CrtYd" user "Package Geometry/Place Bound Top")
		(29 "B.CrtYd" user "Package Geometry/Place Bound Bottom")
		(35 "F.Fab" user "Ref Des/Assembly Top")
		(33 "B.Fab" user "Ref Des/Assembly Bottom")
	)
	(footprint ""
		(layer "F.Cu")
		(at 185.166 -15.113)
		(property "Reference" "FB4G1"
			(at 0 0 0)
			(layer "F.SilkS")
			(hide yes)
			(effects
				(font
					(size 1.27 1.27)
				)
			)
		)
		(property "Value" ""
			(at 0 0 0)
			(layer "F.Fab")
			(effects
				(font
					(size 1.27 1.27)
				)
			)
		)
		(duplicate_pad_numbers_are_jumpers no)
		(fp_rect
			(start -0.7239 2.03835)
			(end 0.7239 -0.26035)
			(stroke
				(width 0)
				(type default)
			)
			(fill no)
			(layer "F.CrtYd")
		)
		(fp_line
			(start -0.7239 -0.26035)
			(end 0.7239 -0.26035)
			(stroke
				(width 0.1)
				(type default)
			)
			(layer "F.Fab")
		)
		(fp_line
			(start -0.7239 2.03835)
			(end -0.7239 -0.26035)
			(stroke
				(width 0.1)
				(type default)
			)
			(layer "F.Fab")
		)
		(fp_line
			(start 0.7239 -0.26035)
			(end 0.7239 2.03835)
			(stroke
				(width 0.1)
				(type default)
			)
			(layer "F.Fab")
		)
		(fp_line
			(start 0.7239 2.03835)
			(end -0.7239 2.03835)
			(stroke
				(width 0.1)
				(type default)
			)
			(layer "F.Fab")
		)
		(pad "1" smd rect
			(at 0 0)
			(size 1.27 1.016)
			(layers "F.Cu" "F.Mask" "F.Paste")
			(net "P12V_STBY")
		)
		(pad "2" smd rect
			(at 0 1.778)
			(size 1.27 1.016)
			(layers "F.Cu" "F.Mask" "F.Paste")
			(net "VR_FET_SW_P12V_STBY_PVPP_GHJ")
		)
		(zone
			(layer "F.Cu")
			(hatch none 0.5)
			(connect_pads
				(clearance 0)
			)
			(min_thickness 0.25)
			(keepout
				(tracks not_allowed)
				(vias allowed)
				(pads allowed)
				(copperpour not_allowed)
				(footprints allowed)
			)
			(placement
				(enabled no)
				(sheetname "")
			)
			(fill
				(thermal_gap 0.5)
				(thermal_bridge_width 0.5)
				(island_removal_mode 0)
			)
			(polygon
				(pts
					(xy 185.801 -14.605) (xy 185.801 -13.843) (xy 185.7121 -13.843) (xy 184.531 -13.843) (xy 184.531 -14.605)
				)
			)
		)
	)
	(footprint ""
		(layer "F.Cu")
		(at 396.468092 -10.968736)
		(property "Reference" "C7G24"
			(at 0 0 0)
			(layer "F.SilkS")
			(hide yes)
			(effects
				(font
					(size 1.27 1.27)
				)
			)
		)
		(property "Value" ""
			(at 0 0 0)
			(layer "F.Fab")
			(effects
				(font
					(size 1.27 1.27)
				)
			)
		)
		(duplicate_pad_numbers_are_jumpers no)
		(fp_rect
			(start -0.3048 0.9906)
			(end 0.3048 -0.1016)
			(stroke
				(width 0)
				(type default)
			)
			(fill no)
			(layer "F.CrtYd")
		)
		(fp_line
			(start -0.3048 -0.1016)
			(end -0.3048 0.9906)
			(stroke
				(width 0.1)
				(type default)
			)
			(layer "F.Fab")
		)
		(fp_line
			(start -0.3048 0.9906)
			(end 0.3048 0.9906)
			(stroke
				(width 0.1)
				(type default)
			)
			(layer "F.Fab")
		)
		(fp_line
			(start 0.3048 -0.1016)
			(end -0.3048 -0.1016)
			(stroke
				(width 0.1)
				(type default)
			)
			(layer "F.Fab")
		)
		(fp_line
			(start 0.3048 0.9906)
			(end 0.3048 -0.1016)
			(stroke
				(width 0.1)
				(type default)
			)
			(layer "F.Fab")
		)
		(pad "1" smd rect
			(at 0 0)
			(size 0.508 0.508)
			(layers "F.Cu" "F.Mask" "F.Paste")
			(net "P3E_CPU0_PE2_SS_TXN<6>")
		)
		(pad "2" smd rect
			(at 0 0.889)
			(size 0.508 0.508)
			(layers "F.Cu" "F.Mask" "F.Paste")
			(net "P3E_CPU0_PE2_SS_C_TXN<6>")
		)
		(zone
			(layer "F.Cu")
			(hatch none 0.5)
			(connect_pads
				(clearance 0)
			)
			(min_thickness 0.25)
			(keepout
				(tracks not_allowed)
				(vias allowed)
				(pads allowed)
				(copperpour not_allowed)
				(footprints allowed)
			)
			(placement
				(enabled no)
				(sheetname "")
			)
			(fill
				(thermal_gap 0.5)
				(thermal_bridge_width 0.5)
				(island_removal_mode 0)
			)
			(polygon
				(pts
					(xy 396.214092 -10.333736) (xy 396.722092 -10.333736) (xy 396.722092 -10.714736) (xy 396.214092 -10.714736)
				)
			)
		)
		(zone
			(layer "F.Cu")
			(hatch none 0.5)
			(connect_pads
				(clearance 0)
			)
			(min_thickness 0.25)
			(keepout
				(tracks allowed)
				(vias not_allowed)
				(pads allowed)
				(copperpour not_allowed)
				(footprints allowed)
			)
			(placement
				(enabled no)
				(sheetname "")
			)
			(fill
				(thermal_gap 0.5)
				(thermal_bridge_width 0.5)
				(island_removal_mode 0)
			)
			(polygon
				(pts
					(xy 396.214092 -10.333736) (xy 396.722092 -10.333736) (xy 396.722092 -10.714736) (xy 396.214092 -10.714736)
				)
			)
		)
	)
	(footprint ""
		(layer "F.Cu")
		(at 198.046594 -76.698856 90)
		(property "Reference" "C4D35"
			(at -0.8382 -0.67818 90)
			(unlocked yes)
			(layer "F.SilkS")
			(effects
				(font
					(size 0.4064 0.254)
					(thickness 0.1524)
				)
				(justify left)
			)
		)
		(property "Value" ""
			(at 0 0 90)
			(layer "F.Fab")
			(effects
				(font
					(size 1.27 1.27)
				)
			)
		)
		(duplicate_pad_numbers_are_jumpers no)
		(fp_poly
			(pts
				(xy 0.3048 -0.1016) (xy 0.3048 0.9906) (xy -0.3048 0.9906) (xy -0.3048 -0.1016)
			)
			(stroke
				(width 0)
				(type default)
			)
			(fill no)
			(layer "F.CrtYd")
		)
		(fp_line
			(start 0.3048 -0.1016)
			(end -0.3048 -0.1016)
			(stroke
				(width 0.1)
				(type default)
			)
			(layer "F.Fab")
		)
		(fp_line
			(start -0.3048 -0.1016)
			(end -0.3048 0.9906)
			(stroke
				(width 0.1)
				(type default)
			)
			(layer "F.Fab")
		)
		(fp_line
			(start 0.3048 0.9906)
			(end 0.3048 -0.1016)
			(stroke
				(width 0.1)
				(type default)
			)
			(layer "F.Fab")
		)
		(fp_line
			(start -0.3048 0.9906)
			(end 0.3048 0.9906)
			(stroke
				(width 0.1)
				(type default)
			)
			(layer "F.Fab")
		)
		(pad "1" smd rect
			(at 0 0 90)
			(size 0.508 0.508)
			(layers "F.Cu" "F.Mask" "F.Paste")
			(net "VR_FET_SW_P12V_STBY_PVCCIN_CPU0")
		)
		(pad "2" smd rect
			(at 0 0.889 90)
			(size 0.508 0.508)
			(layers "F.Cu" "F.Mask" "F.Paste")
			(net "GND")
		)
		(zone
			(layer "F.Cu")
			(hatch none 0.5)
			(connect_pads
				(clearance 0)
			)
			(min_thickness 0.25)
			(keepout
				(tracks allowed)
				(vias not_allowed)
				(pads allowed)
				(copperpour not_allowed)
				(footprints allowed)
			)
			(placement
				(enabled no)
				(sheetname "")
			)
			(fill
				(thermal_gap 0.5)
				(thermal_bridge_width 0.5)
				(island_removal_mode 0)
			)
			(polygon
				(pts
					(xy 198.300594 -76.444856) (xy 198.300594 -76.952856) (xy 198.681594 -76.952856) (xy 198.681594 -76.444856)
				)
			)
		)
		(zone
			(layer "F.Cu")
			(hatch none 0.5)
			(connect_pads
				(clearance 0)
			)
			(min_thickness 0.25)
			(keepout
				(tracks not_allowed)
				(vias allowed)
				(pads allowed)
				(copperpour not_allowed)
				(footprints allowed)
			)
			(placement
				(enabled no)
				(sheetname "")
			)
			(fill
				(thermal_gap 0.5)
				(thermal_bridge_width 0.5)
				(island_removal_mode 0)
			)
			(polygon
				(pts
					(xy 198.681594 -76.444856) (xy 198.681594 -76.952856) (xy 198.300594 -76.952856) (xy 198.300594 -76.444856)
				)
			)
		)
	)
	(footprint ""
		(layer "F.Cu")
		(at -3.175 -144.8562 -90)
		(property "Reference" "R1A2"
			(at 0 0 270)
			(layer "F.SilkS")
			(hide yes)
			(effects
				(font
					(size 1.27 1.27)
				)
			)
		)
		(property "Value" ""
			(at 0 0 270)
			(layer "F.Fab")
			(effects
				(font
					(size 1.27 1.27)
				)
			)
		)
		(duplicate_pad_numbers_are_jumpers no)
		(fp_poly
			(pts
				(xy -0.2794 -0.1016) (xy 0.2794 -0.1016) (xy 0.2794 0.9906) (xy -0.2794 0.9906)
			)
			(stroke
				(width 0)
				(type default)
			)
			(fill no)
			(layer "F.CrtYd")
		)
		(fp_line
			(start -0.2794 0.9906)
			(end 0.2794 0.9906)
			(stroke
				(width 0.1)
				(type default)
			)
			(layer "F.Fab")
		)
		(fp_line
			(start 0.2794 0.9906)
			(end 0.2794 -0.1016)
			(stroke
				(width 0.1)
				(type default)
			)
			(layer "F.Fab")
		)
		(fp_line
			(start -0.2794 -0.1016)
			(end -0.2794 0.9906)
			(stroke
				(width 0.1)
				(type default)
			)
			(layer "F.Fab")
		)
		(fp_line
			(start 0.2794 -0.1016)
			(end -0.2794 -0.1016)
			(stroke
				(width 0.1)
				(type default)
			)
			(layer "F.Fab")
		)
		(pad "1" smd rect
			(at 0 0 270)
			(size 0.508 0.508)
			(layers "F.Cu" "F.Mask" "F.Paste")
			(net "VR_PVDDQ_KLM_PH2_OCSET")
		)
		(pad "2" smd rect
			(at 0 0.889 270)
			(size 0.508 0.508)
			(layers "F.Cu" "F.Mask" "F.Paste")
			(net "GND")
		)
		(zone
			(layer "F.Cu")
			(hatch none 0.5)
			(connect_pads
				(clearance 0)
			)
			(min_thickness 0.25)
			(keepout
				(tracks not_allowed)
				(vias allowed)
				(pads allowed)
				(copperpour not_allowed)
				(footprints allowed)
			)
			(placement
				(enabled no)
				(sheetname "")
			)
			(fill
				(thermal_gap 0.5)
				(thermal_bridge_width 0.5)
				(island_removal_mode 0)
			)
			(polygon
				(pts
					(xy -3.81 -145.1102) (xy -3.81 -144.6022) (xy -3.429 -144.6022) (xy -3.429 -145.1102)
				)
			)
		)
		(zone
			(layer "F.Cu")
			(hatch none 0.5)
			(connect_pads
				(clearance 0)
			)
			(min_thickness 0.25)
			(keepout
				(tracks allowed)
				(vias not_allowed)
				(pads allowed)
				(copperpour not_allowed)
				(footprints allowed)
			)
			(placement
				(enabled no)
				(sheetname "")
			)
			(fill
				(thermal_gap 0.5)
				(thermal_bridge_width 0.5)
				(island_removal_mode 0)
			)
			(polygon
				(pts
					(xy -3.429 -145.1102) (xy -3.429 -144.6022) (xy -3.81 -144.6022) (xy -3.81 -145.1102)
				)
			)
		)
	)
	(footprint ""
		(layer "F.Cu")
		(at 168.07942 -73.662032 180)
		(property "Reference" "R4W5"
			(at -0.8382 -0.67818 180)
			(unlocked yes)
			(layer "F.SilkS")
			(effects
				(font
					(size 0.4064 0.254)
					(thickness 0.1524)
				)
				(justify left)
			)
		)
		(property "Value" ""
			(at 0 0 180)
			(layer "F.Fab")
			(effects
				(font
					(size 1.27 1.27)
				)
			)
		)
		(duplicate_pad_numbers_are_jumpers no)
		(fp_poly
			(pts
				(xy -0.2794 -0.1016) (xy 0.2794 -0.1016) (xy 0.2794 0.9906) (xy -0.2794 0.9906)
			)
			(stroke
				(width 0)
				(type default)
			)
			(fill no)
			(layer "F.CrtYd")
		)
		(fp_line
			(start 0.2794 0.9906)
			(end 0.2794 -0.1016)
			(stroke
				(width 0.1)
				(type default)
			)
			(layer "F.Fab")
		)
		(fp_line
			(start 0.2794 -0.1016)
			(end -0.2794 -0.1016)
			(stroke
				(width 0.1)
				(type default)
			)
			(layer "F.Fab")
		)
		(fp_line
			(start -0.2794 0.9906)
			(end 0.2794 0.9906)
			(stroke
				(width 0.1)
				(type default)
			)
			(layer "F.Fab")
		)
		(fp_line
			(start -0.2794 -0.1016)
			(end -0.2794 0.9906)
			(stroke
				(width 0.1)
				(type default)
			)
			(layer "F.Fab")
		)
		(pad "1" smd rect
			(at 0 0 180)
			(size 0.508 0.508)
			(layers "F.Cu" "F.Mask" "F.Paste")
			(net "FM_DB1200_PWRGD")
		)
		(pad "2" smd rect
			(at 0 0.889 180)
			(size 0.508 0.508)
			(layers "F.Cu" "F.Mask" "F.Paste")
			(net "FM_DB1200_PWRGD_R")
		)
		(zone
			(layer "F.Cu")
			(hatch none 0.5)
			(connect_pads
				(clearance 0)
			)
			(min_thickness 0.25)
			(keepout
				(tracks not_allowed)
				(vias allowed)
				(pads allowed)
				(copperpour not_allowed)
				(footprints allowed)
			)
			(placement
				(enabled no)
				(sheetname "")
			)
			(fill
				(thermal_gap 0.5)
				(thermal_bridge_width 0.5)
				(island_removal_mode 0)
			)
			(polygon
				(pts
					(xy 168.33342 -74.297032) (xy 167.82542 -74.297032) (xy 167.82542 -73.916032) (xy 168.33342 -73.916032)
				)
			)
		)
		(zone
			(layer "F.Cu")
			(hatch none 0.5)
			(connect_pads
				(clearance 0)
			)
			(min_thickness 0.25)
			(keepout
				(tracks allowed)
				(vias not_allowed)
				(pads allowed)
				(copperpour not_allowed)
				(footprints allowed)
			)
			(placement
				(enabled no)
				(sheetname "")
			)
			(fill
				(thermal_gap 0.5)
				(thermal_bridge_width 0.5)
				(island_removal_mode 0)
			)
			(polygon
				(pts
					(xy 168.33342 -73.916032) (xy 167.82542 -73.916032) (xy 167.82542 -74.297032) (xy 168.33342 -74.297032)
				)
			)
		)
	)
	(footprint ""
		(layer "F.Cu")
		(at 194.749928 -92.210382 -90)
		(property "Reference" "C4C18"
			(at 0 0 270)
			(layer "F.SilkS")
			(hide yes)
			(effects
				(font
					(size 1.27 1.27)
				)
			)
		)
		(property "Value" ""
			(at 0 0 270)
			(layer "F.Fab")
			(effects
				(font
					(size 1.27 1.27)
				)
			)
		)
		(duplicate_pad_numbers_are_jumpers no)
		(fp_poly
			(pts
				(xy 0.3048 -0.1016) (xy 0.3048 0.9906) (xy -0.3048 0.9906) (xy -0.3048 -0.1016)
			)
			(stroke
				(width 0)
				(type default)
			)
			(fill no)
			(layer "F.CrtYd")
		)
		(fp_line
			(start -0.3048 0.9906)
			(end 0.3048 0.9906)
			(stroke
				(width 0.1)
				(type default)
			)
			(layer "F.Fab")
		)
		(fp_line
			(start 0.3048 0.9906)
			(end 0.3048 -0.1016)
			(stroke
				(width 0.1)
				(type default)
			)
			(layer "F.Fab")
		)
		(fp_line
			(start -0.3048 -0.1016)
			(end -0.3048 0.9906)
			(stroke
				(width 0.1)
				(type default)
			)
			(layer "F.Fab")
		)
		(fp_line
			(start 0.3048 -0.1016)
			(end -0.3048 -0.1016)
			(stroke
				(width 0.1)
				(type default)
			)
			(layer "F.Fab")
		)
		(pad "1" smd rect
			(at 0 0 270)
			(size 0.508 0.508)
			(layers "F.Cu" "F.Mask" "F.Paste")
			(net "VR_FET_SW_P12V_STBY_PVCCIN_CPU0")
		)
		(pad "2" smd rect
			(at 0 0.889 270)
			(size 0.508 0.508)
			(layers "F.Cu" "F.Mask" "F.Paste")
			(net "GND")
		)
		(zone
			(layer "F.Cu")
			(hatch none 0.5)
			(connect_pads
				(clearance 0)
			)
			(min_thickness 0.25)
			(keepout
				(tracks not_allowed)
				(vias allowed)
				(pads allowed)
				(copperpour not_allowed)
				(footprints allowed)
			)
			(placement
				(enabled no)
				(sheetname "")
			)
			(fill
				(thermal_gap 0.5)
				(thermal_bridge_width 0.5)
				(island_removal_mode 0)
			)
			(polygon
				(pts
					(xy 194.114928 -92.464382) (xy 194.114928 -91.956382) (xy 194.495928 -91.956382) (xy 194.495928 -92.464382)
				)
			)
		)
		(zone
			(layer "F.Cu")
			(hatch none 0.5)
			(connect_pads
				(clearance 0)
			)
			(min_thickness 0.25)
			(keepout
				(tracks allowed)
				(vias not_allowed)
				(pads allowed)
				(copperpour not_allowed)
				(footprints allowed)
			)
			(placement
				(enabled no)
				(sheetname "")
			)
			(fill
				(thermal_gap 0.5)
				(thermal_bridge_width 0.5)
				(island_removal_mode 0)
			)
			(polygon
				(pts
					(xy 194.495928 -92.464382) (xy 194.495928 -91.956382) (xy 194.114928 -91.956382) (xy 194.114928 -92.464382)
				)
			)
		)
	)
	(footprint ""
		(layer "F.Cu")
		(at 357.000048 -155.10002 90)
		(property "Reference" "TH7A1"
			(at -4.27609 8.277352 0)
			(unlocked yes)
			(layer "F.SilkS")
			(effects
				(font
					(size 0.7874 0.5842)
					(thickness 0.1524)
				)
				(justify left)
			)
		)
		(property "Value" ""
			(at 0 0 90)
			(layer "F.Fab")
			(effects
				(font
					(size 1.27 1.27)
				)
			)
		)
		(duplicate_pad_numbers_are_jumpers no)
		(fp_poly
			(pts
				(arc
					(start 3.0226 0.68834)
					(mid 3.042235 0.827855)
					(end 3.099562 0.956564)
				)
				(arc
					(start 3.099562 0.956564)
					(mid 4.012804 3.550073)
					(end 3.042158 6.12267)
				)
				(arc
					(start 3.042158 6.12267)
					(mid 0 7.518589)
					(end -3.042158 6.12267)
				)
				(arc
					(start -3.042158 6.12267)
					(mid -4.012854 3.55061)
					(end -3.100324 0.957326)
				)
				(arc
					(start -3.100324 0.957326)
					(mid -3.042498 0.827518)
					(end -3.0226 0.686816)
				)
				(arc
					(start -3.0226 -0.000254)
					(mid -2.137121 -2.137227)
					(end 0 -3.022346)
				)
				(arc
					(start 0 -3.022346)
					(mid 2.137227 -2.136973)
					(end 3.0226 0.000254)
				)
			)
			(stroke
				(width 0)
				(type default)
			)
			(fill no)
			(layer "F.CrtYd")
		)
		(pad "1" thru_hole custom
			(at 0 0 90)
			(size 2.00667 2.00667)
			(drill 0.3048)
			(layers "*.Cu" "*.Mask")
			(remove_unused_layers no)
			(net "GND")
			(clearance -0.889)
			(options
				(clearance outline)
				(anchor circle)
			)
			(primitives
				(gr_poly
					(pts
						(arc
							(start 3.042158 3.874516)
							(mid 0 5.270435)
							(end -3.042158 3.874516)
						)
						(arc
							(start -3.042158 3.874516)
							(mid -4.012854 1.302456)
							(end -3.100324 -1.290828)
						)
						(arc
							(start -3.100324 -1.290828)
							(mid -3.042498 -1.420636)
							(end -3.0226 -1.561338)
						)
						(arc
							(start -3.0226 -2.248408)
							(mid -2.137121 -4.385381)
							(end 0 -5.2705)
						)
						(arc
							(start 0 -5.2705)
							(mid 2.137227 -4.385127)
							(end 3.0226 -2.2479)
						)
						(arc
							(start 3.0226 -1.55956)
							(mid 3.04227 -1.420177)
							(end 3.099562 -1.29159)
						)
						(arc
							(start 3.099562 -1.29159)
							(mid 4.012804 1.301919)
							(end 3.042158 3.874516)
						)
					)
					(width 0)
					(fill yes)
				)
			)
		)
	)
	(footprint ""
		(layer "F.Cu")
		(at 271.9832 -79.6036 180)
		(property "Reference" "C5W2"
			(at 0.97536 0.76708 90)
			(unlocked yes)
			(layer "F.SilkS")
			(effects
				(font
					(size 0.4064 0.254)
					(thickness 0.1524)
				)
			)
		)
		(property "Value" ""
			(at 0 0 180)
			(layer "F.Fab")
			(effects
				(font
					(size 1.27 1.27)
				)
			)
		)
		(duplicate_pad_numbers_are_jumpers no)
		(fp_poly
			(pts
				(xy -0.4953 -0.2032) (xy 0.4953 -0.2032) (xy 0.4953 1.6002) (xy -0.4953 1.6002)
			)
			(stroke
				(width 0)
				(type default)
			)
			(fill no)
			(layer "F.CrtYd")
		)
		(fp_line
			(start 0.4953 1.6002)
			(end -0.4953 1.6002)
			(stroke
				(width 0.1)
				(type default)
			)
			(layer "F.Fab")
		)
		(fp_line
			(start 0.4953 -0.2032)
			(end 0.4953 1.6002)
			(stroke
				(width 0.1)
				(type default)
			)
			(layer "F.Fab")
		)
		(fp_line
			(start -0.4953 1.6002)
			(end -0.4953 -0.2032)
			(stroke
				(width 0.1)
				(type default)
			)
			(layer "F.Fab")
		)
		(fp_line
			(start -0.4953 -0.2032)
			(end 0.4953 -0.2032)
			(stroke
				(width 0.1)
				(type default)
			)
			(layer "F.Fab")
		)
		(pad "1" smd rect
			(at 0 0 180)
			(size 0.762 0.889)
			(layers "F.Cu" "F.Mask" "F.Paste")
			(net "PVCCMCP_CPU0")
		)
		(pad "2" smd rect
			(at 0 1.397 180)
			(size 0.762 0.889)
			(layers "F.Cu" "F.Mask" "F.Paste")
			(net "GND")
		)
		(zone
			(layer "F.Cu")
			(hatch none 0.5)
			(connect_pads
				(clearance 0)
			)
			(min_thickness 0.25)
			(keepout
				(tracks not_allowed)
				(vias allowed)
				(pads allowed)
				(copperpour not_allowed)
				(footprints allowed)
			)
			(placement
				(enabled no)
				(sheetname "")
			)
			(fill
				(thermal_gap 0.5)
				(thermal_bridge_width 0.5)
				(island_removal_mode 0)
			)
			(polygon
				(pts
					(xy 272.3642 -80.0481) (xy 271.6022 -80.0481) (xy 271.6022 -80.5561) (xy 272.3642 -80.5561)
				)
			)
		)
	)
)
